(kicad_pcb
	(version 20260206)
	(generator "pcbnew")
	(generator_version "10.0")
	(general
		(thickness 1.6)
		(legacy_teardrops no)
	)
	(paper "A4")
	(title_block
		(title "timecard-production-celestica-r4006 — R4006-B0001-02_R01.brd")
		(comment 1 "Time Appliance Project (Time Card) / footprints 229-232 of 1113")
	)
	(layers
		(0 "F.Cu" signal "TOP")
		(4 "In1.Cu" signal "L02_GND1")
		(6 "In2.Cu" signal "L03_SIG1")
		(8 "In3.Cu" signal "L04_GND2")
		(10 "In4.Cu" signal "L05_VCC1")
		(12 "In5.Cu" signal "L06_VCC2")
		(14 "In6.Cu" signal "L07_GND3")
		(16 "In7.Cu" signal "L08_SIG2")
		(18 "In8.Cu" signal "L09_GND4")
		(2 "B.Cu" signal "BOTTOM")
		(9 "F.Adhes" user "F.Adhesive")
		(11 "B.Adhes" user "B.Adhesive")
		(13 "F.Paste" user "Package Geometry/Pastemask Top")
		(15 "B.Paste" user "Package Geometry/Pastemask Bottom")
		(5 "F.SilkS" user "Ref Des/Silkscreen Top")
		(7 "B.SilkS" user "Ref Des/Silkscreen Bottom")
		(1 "F.Mask" user "Board Geometry/Soldermask Top")
		(3 "B.Mask" user "Board Geometry/Soldermask Bottom")
		(17 "Dwgs.User" user "User.Drawings")
		(19 "Cmts.User" user "User.Comments")
		(21 "Eco1.User" user "User.Eco1")
		(23 "Eco2.User" user "User.Eco2")
		(25 "Edge.Cuts" user "Board Geometry/Outline")
		(27 "Margin" user)
		(31 "F.CrtYd" user "Package Geometry/Place Bound Top")
		(29 "B.CrtYd" user "Package Geometry/Place Bound Bottom")
		(35 "F.Fab" user "Ref Des/Assembly Top")
		(33 "B.Fab" user "Ref Des/Assembly Bottom")
	)
	(footprint ""
		(layer "F.Cu")
		(at 152.146 -53.1876 90)
		(property "Reference" "U27"
			(at -0.7366 2.45237 90)
			(unlocked yes)
			(layer "F.SilkS")
			(effects
				(font
					(size 0.7874 0.5842)
					(thickness 0.1524)
				)
			)
		)
		(property "Value" ""
			(at 0 0 90)
			(layer "F.Fab")
			(effects
				(font
					(size 1.27 1.27)
				)
			)
		)
		(property "Device Type" "SHT31A_DIS_B10KS_DFN8-A222-000A"
			(at 0 3.831336 90)
			(unlocked yes)
			(layer "F.Fab")
			(hide yes)
			(effects
				(font
					(size 0.7874 0.5842)
					(thickness 0.1524)
				)
			)
		)
		(property "User Part Number" "PARTNUM*"
			(at 0 5.025136 90)
			(unlocked yes)
			(layer "Cmts.User")
			(hide yes)
			(effects
				(font
					(size 0.7874 0.5842)
					(thickness 0.1524)
				)
			)
		)
		(duplicate_pad_numbers_are_jumpers no)
		(fp_line
			(start 2.040128 -1.553972)
			(end 2.040128 1.553972)
			(stroke
				(width 0.1)
				(type default)
			)
			(layer "F.SilkS")
		)
		(fp_line
			(start -2.040128 -1.553972)
			(end 2.040128 -1.553972)
			(stroke
				(width 0.1)
				(type default)
			)
			(layer "F.SilkS")
		)
		(fp_line
			(start 2.040128 1.553972)
			(end -2.040128 1.553972)
			(stroke
				(width 0.1)
				(type default)
			)
			(layer "F.SilkS")
		)
		(fp_line
			(start -2.040128 1.553972)
			(end -2.040128 -1.553972)
			(stroke
				(width 0.1)
				(type default)
			)
			(layer "F.SilkS")
		)
		(fp_poly
			(pts
				(arc
					(start -2.5146 -2.032)
					(mid -2.5146 -3.048)
					(end -2.5146 -2.032)
				)
			)
			(stroke
				(width 0)
				(type default)
			)
			(fill yes)
			(layer "F.SilkS")
		)
		(fp_poly
			(pts
				(xy 0.4953 0.1016) (xy 0.4953 0.9017) (xy -0.22098 0.9017)
				(arc
					(start -0.221742 0.900938)
					(mid -0.054914 0.820246)
					(end 0.0127 0.6477)
				)
				(arc
					(start 0.0127 0.6477)
					(mid -0.061695 0.468095)
					(end -0.2413 0.3937)
				)
				(arc
					(start -0.2413 0.3937)
					(mid -0.412633 0.460187)
					(end -0.494284 0.62484)
				)
				(xy -0.4953 0.62484) (xy -0.4953 0.1016)
			)
			(stroke
				(width 0)
				(type default)
			)
			(fill yes)
			(layer "F.Paste")
		)
		(fp_poly
			(pts
				(xy 0.4953 -0.63754) (xy 0.4953 -0.1016) (xy -0.4953 -0.1016) (xy -0.4953 -0.9017) (xy 0.22606 -0.9017)
				(arc
					(start 0.22606 -0.901192)
					(mid 0.056421 -0.821798)
					(end -0.0127 -0.6477)
				)
				(arc
					(start -0.0127 -0.6477)
					(mid 0.061695 -0.468095)
					(end 0.2413 -0.3937)
				)
				(arc
					(start 0.2413 -0.3937)
					(mid 0.417276 -0.464537)
					(end 0.495046 -0.63754)
				)
			)
			(stroke
				(width 0)
				(type default)
			)
			(fill yes)
			(layer "F.Paste")
		)
		(fp_rect
			(start -2.294128 1.807972)
			(end 2.294128 -1.807972)
			(stroke
				(width 0)
				(type default)
			)
			(fill no)
			(layer "F.CrtYd")
		)
		(fp_line
			(start 1.299972 -1.299972)
			(end -1.299972 -1.299972)
			(stroke
				(width 0.1)
				(type default)
			)
			(layer "F.Fab")
		)
		(fp_line
			(start -1.299972 -1.299972)
			(end -1.299972 1.299972)
			(stroke
				(width 0.1)
				(type default)
			)
			(layer "F.Fab")
		)
		(fp_line
			(start 1.299972 1.299972)
			(end 1.299972 -1.299972)
			(stroke
				(width 0.1)
				(type default)
			)
			(layer "F.Fab")
		)
		(fp_line
			(start -1.299972 1.299972)
			(end 1.299972 1.299972)
			(stroke
				(width 0.1)
				(type default)
			)
			(layer "F.Fab")
		)
		(fp_poly
			(pts
				(arc
					(start -2.3876 -1.143)
					(mid -2.3876 -2.159)
					(end -2.3876 -1.143)
				)
			)
			(stroke
				(width 0)
				(type default)
			)
			(fill yes)
			(layer "F.Fab")
		)
		(fp_text user "8"
			(at 2.4384 -1.86563 90)
			(unlocked yes)
			(layer "F.SilkS")
			(effects
				(font
					(size 0.7874 0.5842)
					(thickness 0.1524)
				)
			)
		)
		(fp_text user "4"
			(at -2.6416 1.43637 90)
			(unlocked yes)
			(layer "F.SilkS")
			(effects
				(font
					(size 0.7874 0.5842)
					(thickness 0.1524)
				)
			)
		)
		(fp_text user "5"
			(at 2.4384 1.56337 90)
			(unlocked yes)
			(layer "F.SilkS")
			(effects
				(font
					(size 0.7874 0.5842)
					(thickness 0.1524)
				)
			)
		)
		(fp_text user "8"
			(at 2.14503 -1.524 0)
			(unlocked yes)
			(layer "F.Fab")
			(effects
				(font
					(size 0.7874 0.5842)
					(thickness 0.1524)
				)
			)
		)
		(fp_text user "5"
			(at 1.89103 1.397 0)
			(unlocked yes)
			(layer "F.Fab")
			(effects
				(font
					(size 0.7874 0.5842)
					(thickness 0.1524)
				)
			)
		)
		(fp_text user "4"
			(at -2.17297 1.905 0)
			(unlocked yes)
			(layer "F.Fab")
			(effects
				(font
					(size 0.7874 0.5842)
					(thickness 0.1524)
				)
			)
		)
		(pad "1" smd rect
			(at -1.265428 -0.750062 90)
			(size 1.0414 0.3048)
			(layers "F.Cu" "F.Mask" "F.Paste")
			(net "R_SHT3X_I2C_SDA")
		)
		(pad "2" smd rect
			(at -1.265428 -0.249936 90)
			(size 1.0414 0.3048)
			(layers "F.Cu" "F.Mask" "F.Paste")
			(net "SHT3X_ADDR")
		)
		(pad "3" smd rect
			(at -1.265428 0.249936 90)
			(size 1.0414 0.3048)
			(layers "F.Cu" "F.Mask" "F.Paste")
			(net "R_SHT3X_ALERT_N")
		)
		(pad "4" smd rect
			(at -1.265428 0.750062 90)
			(size 1.0414 0.3048)
			(layers "F.Cu" "F.Mask" "F.Paste")
			(net "R_SHT3X_I2C_SCL")
		)
		(pad "5" smd rect
			(at 1.265428 0.750062 90)
			(size 1.0414 0.3048)
			(layers "F.Cu" "F.Mask" "F.Paste")
			(net "VDD3V3_SHT31A")
		)
		(pad "6" smd rect
			(at 1.265428 0.249936 90)
			(size 1.0414 0.3048)
			(layers "F.Cu" "F.Mask" "F.Paste")
			(net "R_SHT3X_RST_N")
		)
		(pad "7" smd rect
			(at 1.265428 -0.249936 90)
			(size 1.0414 0.3048)
			(layers "F.Cu" "F.Mask" "F.Paste")
			(net "SG")
		)
		(pad "8" smd rect
			(at 1.265428 -0.750062 90)
			(size 1.0414 0.3048)
			(layers "F.Cu" "F.Mask" "F.Paste")
			(net "SG")
		)
		(pad "9" smd rect
			(at 0 0 90)
			(size 0.9906 1.8034)
			(layers "F.Cu" "F.Mask" "F.Paste")
			(net "SG")
		)
	)
	(footprint ""
		(layer "F.Cu")
		(at 56.7944 -98.0694 -90)
		(property "Reference" "C13"
			(at -0.127 -3.59537 90)
			(unlocked yes)
			(layer "F.SilkS")
			(effects
				(font
					(size 0.7874 0.5842)
					(thickness 0.1524)
				)
			)
		)
		(property "Value" "VAL*"
			(at 0.0762 3.134106 270)
			(unlocked yes)
			(layer "F.Fab")
			(hide yes)
			(effects
				(font
					(size 0.7874 0.5842)
					(thickness 0.1524)
				)
			)
		)
		(property "Device Type" "CAPACITOR-G107-0F226-CM,22UF,2A"
			(at 0.0508 2.194306 270)
			(unlocked yes)
			(layer "F.Fab")
			(hide yes)
			(effects
				(font
					(size 0.7874 0.5842)
					(thickness 0.1524)
				)
			)
		)
		(property "User Part Number" "PARTNUM*"
			(at 0.1016 5.013706 270)
			(unlocked yes)
			(layer "Cmts.User")
			(hide yes)
			(effects
				(font
					(size 0.7874 0.5842)
					(thickness 0.1524)
				)
			)
		)
		(property "Tolerance" "TOL*"
			(at 0.0762 4.048506 270)
			(unlocked yes)
			(layer "Cmts.User")
			(hide yes)
			(effects
				(font
					(size 0.7874 0.5842)
					(thickness 0.1524)
				)
			)
		)
		(duplicate_pad_numbers_are_jumpers no)
		(fp_line
			(start -1.5748 0.9398)
			(end 1.5748 0.9398)
			(stroke
				(width 0.1)
				(type default)
			)
			(layer "F.SilkS")
		)
		(fp_line
			(start 1.5748 0.9398)
			(end 1.5748 -0.9398)
			(stroke
				(width 0.1)
				(type default)
			)
			(layer "F.SilkS")
		)
		(fp_line
			(start -1.5748 -0.9398)
			(end -1.5748 0.9398)
			(stroke
				(width 0.1)
				(type default)
			)
			(layer "F.SilkS")
		)
		(fp_line
			(start 1.5748 -0.9398)
			(end -1.5748 -0.9398)
			(stroke
				(width 0.1)
				(type default)
			)
			(layer "F.SilkS")
		)
		(fp_rect
			(start -1.5748 -0.9398)
			(end 1.5748 0.9398)
			(stroke
				(width 0)
				(type default)
			)
			(fill no)
			(layer "F.CrtYd")
		)
		(fp_line
			(start -1.016 0.635)
			(end 1.016 0.635)
			(stroke
				(width 0.1)
				(type default)
			)
			(layer "F.Fab")
		)
		(fp_line
			(start 1.016 0.635)
			(end 1.016 -0.635)
			(stroke
				(width 0.1)
				(type default)
			)
			(layer "F.Fab")
		)
		(fp_line
			(start -1.016 -0.635)
			(end -1.016 0.635)
			(stroke
				(width 0.1)
				(type default)
			)
			(layer "F.Fab")
		)
		(fp_line
			(start 1.016 -0.635)
			(end -1.016 -0.635)
			(stroke
				(width 0.1)
				(type default)
			)
			(layer "F.Fab")
		)
		(pad "1" smd rect
			(at -0.8382 0 270)
			(size 0.9652 1.3716)
			(layers "F.Cu" "F.Mask" "F.Paste")
			(net "XP5R0V")
		)
		(pad "2" smd rect
			(at 0.8382 0 270)
			(size 0.9652 1.3716)
			(layers "F.Cu" "F.Mask" "F.Paste")
			(net "SG")
		)
		(zone
			(layer "F.Cu")
			(hatch none 0.5)
			(connect_pads
				(clearance 0)
			)
			(min_thickness 0.25)
			(keepout
				(tracks allowed)
				(vias not_allowed)
				(pads allowed)
				(copperpour not_allowed)
				(footprints allowed)
			)
			(placement
				(enabled no)
				(sheetname "")
			)
			(fill
				(thermal_gap 0.5)
				(thermal_bridge_width 0.5)
				(island_removal_mode 0)
			)
			(polygon
				(pts
					(xy 57.4294 -98.298) (xy 56.1594 -98.298) (xy 56.1594 -97.8408) (xy 57.4294 -97.8408)
				)
			)
		)
	)
	(footprint ""
		(layer "F.Cu")
		(at 20.32 -30.48 180)
		(property "Reference" "R390"
			(at -2.794 -0.80137 0)
			(unlocked yes)
			(layer "F.SilkS")
			(effects
				(font
					(size 0.7874 0.5842)
					(thickness 0.1524)
				)
			)
		)
		(property "Value" "VAL*"
			(at 0.02032 2.13233 180)
			(unlocked yes)
			(layer "F.Fab")
			(hide yes)
			(effects
				(font
					(size 0.7874 0.5842)
					(thickness 0.1524)
				)
			)
		)
		(property "Tolerance" "TOL*"
			(at 0.044704 3.05435 180)
			(unlocked yes)
			(layer "Cmts.User")
			(hide yes)
			(effects
				(font
					(size 0.7874 0.5842)
					(thickness 0.1524)
				)
			)
		)
		(property "User Part Number" "PARTNUM*"
			(at 0.02032 4.024884 180)
			(unlocked yes)
			(layer "Cmts.User")
			(hide yes)
			(effects
				(font
					(size 0.7874 0.5842)
					(thickness 0.1524)
				)
			)
		)
		(property "Device Type" "RESISTOR-G155-133R0-01,33OHM,1%"
			(at 0.008382 1.210564 180)
			(unlocked yes)
			(layer "F.Fab")
			(hide yes)
			(effects
				(font
					(size 0.7874 0.5842)
					(thickness 0.1524)
				)
			)
		)
		(duplicate_pad_numbers_are_jumpers no)
		(fp_line
			(start 1.143 0.5588)
			(end 1.143 -0.5588)
			(stroke
				(width 0.1)
				(type default)
			)
			(layer "F.SilkS")
		)
		(fp_line
			(start 1.143 -0.5588)
			(end -1.143 -0.5588)
			(stroke
				(width 0.1)
				(type default)
			)
			(layer "F.SilkS")
		)
		(fp_line
			(start -1.143 0.5588)
			(end 1.143 0.5588)
			(stroke
				(width 0.1)
				(type default)
			)
			(layer "F.SilkS")
		)
		(fp_line
			(start -1.143 -0.5588)
			(end -1.143 0.5588)
			(stroke
				(width 0.1)
				(type default)
			)
			(layer "F.SilkS")
		)
		(fp_rect
			(start -1.143 -0.5588)
			(end 1.143 0.5588)
			(stroke
				(width 0)
				(type default)
			)
			(fill no)
			(layer "F.CrtYd")
		)
		(fp_line
			(start 0.508 0.3048)
			(end 0.508 -0.3048)
			(stroke
				(width 0.1)
				(type default)
			)
			(layer "F.Fab")
		)
		(fp_line
			(start 0.508 -0.3048)
			(end -0.508 -0.3048)
			(stroke
				(width 0.1)
				(type default)
			)
			(layer "F.Fab")
		)
		(fp_line
			(start -0.508 0.3048)
			(end 0.508 0.3048)
			(stroke
				(width 0.1)
				(type default)
			)
			(layer "F.Fab")
		)
		(fp_line
			(start -0.508 -0.3048)
			(end -0.508 0.3048)
			(stroke
				(width 0.1)
				(type default)
			)
			(layer "F.Fab")
		)
		(pad "1" smd rect
			(at -0.5334 0 180)
			(size 0.7112 0.6096)
			(layers "F.Cu" "F.Mask" "F.Paste")
			(net "SMA2_LED_RED_N")
		)
		(pad "2" smd rect
			(at 0.5334 0 180)
			(size 0.7112 0.6096)
			(layers "F.Cu" "F.Mask" "F.Paste")
			(net "UNNAMED_14_LED4PV14_I266_3")
		)
		(zone
			(layer "F.Cu")
			(hatch none 0.5)
			(connect_pads
				(clearance 0)
			)
			(min_thickness 0.25)
			(keepout
				(tracks not_allowed)
				(vias allowed)
				(pads allowed)
				(copperpour not_allowed)
				(footprints allowed)
			)
			(placement
				(enabled no)
				(sheetname "")
			)
			(fill
				(thermal_gap 0.5)
				(thermal_bridge_width 0.5)
				(island_removal_mode 0)
			)
			(polygon
				(pts
					(xy 20.3962 -30.1752) (xy 20.3962 -30.7848) (xy 20.2438 -30.7848) (xy 20.2438 -30.1752)
				)
			)
		)
		(zone
			(layer "F.Cu")
			(hatch none 0.5)
			(connect_pads
				(clearance 0)
			)
			(min_thickness 0.25)
			(keepout
				(tracks allowed)
				(vias not_allowed)
				(pads allowed)
				(copperpour not_allowed)
				(footprints allowed)
			)
			(placement
				(enabled no)
				(sheetname "")
			)
			(fill
				(thermal_gap 0.5)
				(thermal_bridge_width 0.5)
				(island_removal_mode 0)
			)
			(polygon
				(pts
					(xy 20.3962 -30.1752) (xy 20.3962 -30.7848) (xy 20.2438 -30.7848) (xy 20.2438 -30.1752)
				)
			)
		)
	)
	(footprint ""
		(layer "F.Cu")
		(at 115.1382 -81.788 180)
		(property "Reference" "R459"
			(at -0.4318 -1.18237 0)
			(unlocked yes)
			(layer "F.SilkS")
			(effects
				(font
					(size 0.7874 0.5842)
					(thickness 0.1524)
				)
			)
		)
		(property "Value" "VAL*"
			(at 0.02032 2.13233 180)
			(unlocked yes)
			(layer "F.Fab")
			(hide yes)
			(effects
				(font
					(size 0.7874 0.5842)
					(thickness 0.1524)
				)
			)
		)
		(property "Tolerance" "TOL*"
			(at 0.044704 3.05435 180)
			(unlocked yes)
			(layer "Cmts.User")
			(hide yes)
			(effects
				(font
					(size 0.7874 0.5842)
					(thickness 0.1524)
				)
			)
		)
		(property "User Part Number" "PARTNUM*"
			(at 0.02032 4.024884 180)
			(unlocked yes)
			(layer "Cmts.User")
			(hide yes)
			(effects
				(font
					(size 0.7874 0.5842)
					(thickness 0.1524)
				)
			)
		)
		(property "Device Type" "RESISTOR-G155-11001-01,1KOHM,1%"
			(at 0.008382 1.210564 180)
			(unlocked yes)
			(layer "F.Fab")
			(hide yes)
			(effects
				(font
					(size 0.7874 0.5842)
					(thickness 0.1524)
				)
			)
		)
		(duplicate_pad_numbers_are_jumpers no)
		(fp_line
			(start 1.143 0.5588)
			(end 1.143 -0.5588)
			(stroke
				(width 0.1)
				(type default)
			)
			(layer "F.SilkS")
		)
		(fp_line
			(start 1.143 -0.5588)
			(end -1.143 -0.5588)
			(stroke
				(width 0.1)
				(type default)
			)
			(layer "F.SilkS")
		)
		(fp_line
			(start -1.143 0.5588)
			(end 1.143 0.5588)
			(stroke
				(width 0.1)
				(type default)
			)
			(layer "F.SilkS")
		)
		(fp_line
			(start -1.143 -0.5588)
			(end -1.143 0.5588)
			(stroke
				(width 0.1)
				(type default)
			)
			(layer "F.SilkS")
		)
		(fp_poly
			(pts
				(xy -1.143 0.5588) (xy 1.143 0.5588) (xy 1.143 -0.5588) (xy -1.143 -0.5588)
			)
			(stroke
				(width 0)
				(type default)
			)
			(fill no)
			(layer "F.CrtYd")
		)
		(fp_line
			(start 0.508 0.3048)
			(end 0.508 -0.3048)
			(stroke
				(width 0.1)
				(type default)
			)
			(layer "F.Fab")
		)
		(fp_line
			(start 0.508 -0.3048)
			(end -0.508 -0.3048)
			(stroke
				(width 0.1)
				(type default)
			)
			(layer "F.Fab")
		)
		(fp_line
			(start -0.508 0.3048)
			(end 0.508 0.3048)
			(stroke
				(width 0.1)
				(type default)
			)
			(layer "F.Fab")
		)
		(fp_line
			(start -0.508 -0.3048)
			(end -0.508 0.3048)
			(stroke
				(width 0.1)
				(type default)
			)
			(layer "F.Fab")
		)
		(pad "1" smd rect
			(at -0.5334 0 180)
			(size 0.7112 0.6096)
			(layers "F.Cu" "F.Mask" "F.Paste")
			(net "SG")
		)
		(pad "2" smd rect
			(at 0.5334 0 180)
			(size 0.7112 0.6096)
			(layers "F.Cu" "F.Mask" "F.Paste")
			(net "UNNAMED_524_RESISTOR_I432_2")
		)
		(zone
			(layer "F.Cu")
			(hatch none 0.5)
			(connect_pads
				(clearance 0)
			)
			(min_thickness 0.25)
			(keepout
				(tracks not_allowed)
				(vias allowed)
				(pads allowed)
				(copperpour not_allowed)
				(footprints allowed)
			)
			(placement
				(enabled no)
				(sheetname "")
			)
			(fill
				(thermal_gap 0.5)
				(thermal_bridge_width 0.5)
				(island_removal_mode 0)
			)
			(polygon
				(pts
					(xy 115.2144 -82.0928) (xy 115.062 -82.0928) (xy 115.062 -81.4832) (xy 115.2144 -81.4832)
				)
			)
		)
		(zone
			(layer "F.Cu")
			(hatch none 0.5)
			(connect_pads
				(clearance 0)
			)
			(min_thickness 0.25)
			(keepout
				(tracks allowed)
				(vias not_allowed)
				(pads allowed)
				(copperpour not_allowed)
				(footprints allowed)
			)
			(placement
				(enabled no)
				(sheetname "")
			)
			(fill
				(thermal_gap 0.5)
				(thermal_bridge_width 0.5)
				(island_removal_mode 0)
			)
			(polygon
				(pts
					(xy 115.2144 -82.0928) (xy 115.062 -82.0928) (xy 115.062 -81.4832) (xy 115.2144 -81.4832)
				)
			)
		)
	)
)
